(kicad_pcb
	(version 20260206)
	(generator "pcbnew")
	(generator_version "10.0")
	(general
		(thickness 1.6)
		(legacy_teardrops no)
	)
	(paper "A4")
	(title_block
		(title "03242023_DA0F0TMBIJ0_F0T_Motherboard_J_brd_V01_OCP.brd")
		(comment 1 "Grand Teton / footprints 4784-4790 of 6105")
	)
	(layers
		(0 "F.Cu" signal "TOP")
		(4 "In1.Cu" signal "GND")
		(6 "In2.Cu" signal "IN1")
		(8 "In3.Cu" signal "GND1")
		(10 "In4.Cu" signal "IN2")
		(12 "In5.Cu" signal "GND2")
		(14 "In6.Cu" signal "IN3")
		(16 "In7.Cu" signal "GND3")
		(18 "In8.Cu" signal "VCC")
		(20 "In9.Cu" signal "VCC1")
		(22 "In10.Cu" signal "GND4")
		(24 "In11.Cu" signal "IN4")
		(26 "In12.Cu" signal "GND5")
		(28 "In13.Cu" signal "IN5")
		(30 "In14.Cu" signal "GND6")
		(32 "In15.Cu" signal "IN6")
		(34 "In16.Cu" signal "GND7")
		(2 "B.Cu" signal "BOTTOM")
		(9 "F.Adhes" user "F.Adhesive")
		(11 "B.Adhes" user "B.Adhesive")
		(13 "F.Paste" user "Package Geometry/Pastemask Top")
		(15 "B.Paste" user "Package Geometry/Pastemask Bottom")
		(5 "F.SilkS" user "Ref Des/Silkscreen Top")
		(7 "B.SilkS" user "Ref Des/Silkscreen Bottom")
		(1 "F.Mask" user "Board Geometry/Soldermask Top")
		(3 "B.Mask" user "Board Geometry/Soldermask Bottom")
		(17 "Dwgs.User" user "User.Drawings")
		(19 "Cmts.User" user "User.Comments")
		(21 "Eco1.User" user "User.Eco1")
		(23 "Eco2.User" user "User.Eco2")
		(25 "Edge.Cuts" user "Board Geometry/Outline")
		(27 "Margin" user)
		(31 "F.CrtYd" user "Package Geometry/Place Bound Top")
		(29 "B.CrtYd" user "Package Geometry/Place Bound Bottom")
		(35 "F.Fab" user "Ref Des/Assembly Top")
		(33 "B.Fab" user "Ref Des/Assembly Bottom")
	)
	(footprint ""
		(layer "B.Cu")
		(at 428.669958 -118.6053)
		(property "Reference" "PR375"
			(at 0 0 0)
			(layer "B.SilkS")
			(hide yes)
			(effects
				(font
					(size 1.27 1.27)
				)
				(justify mirror)
			)
		)
		(property "Value" ""
			(at 0 0 0)
			(layer "B.Fab")
			(effects
				(font
					(size 1.27 1.27)
				)
				(justify mirror)
			)
		)
		(duplicate_pad_numbers_are_jumpers no)
		(fp_line
			(start -0.7874 -0.4064)
			(end -0.7874 0.4064)
			(stroke
				(width 0.1524)
				(type default)
			)
			(layer "B.SilkS")
		)
		(fp_line
			(start -0.7874 0.4064)
			(end 0.7874 0.4064)
			(stroke
				(width 0.1524)
				(type default)
			)
			(layer "B.SilkS")
		)
		(fp_line
			(start 0.7874 -0.4064)
			(end -0.7874 -0.4064)
			(stroke
				(width 0.1524)
				(type default)
			)
			(layer "B.SilkS")
		)
		(fp_line
			(start 0.7874 0.4064)
			(end 0.7874 -0.4064)
			(stroke
				(width 0.1524)
				(type default)
			)
			(layer "B.SilkS")
		)
		(fp_line
			(start -0.67945 -0.3048)
			(end -0.67945 0.3048)
			(stroke
				(width 0.1)
				(type default)
			)
			(layer "B.Fab")
		)
		(fp_line
			(start -0.67945 0.3048)
			(end -0.120396 0.3048)
			(stroke
				(width 0.1)
				(type default)
			)
			(layer "B.Fab")
		)
		(fp_line
			(start -0.12065 -0.3048)
			(end -0.67945 -0.3048)
			(stroke
				(width 0.1)
				(type default)
			)
			(layer "B.Fab")
		)
		(fp_line
			(start -0.12065 -0.2794)
			(end -0.12065 -0.3048)
			(stroke
				(width 0.1)
				(type default)
			)
			(layer "B.Fab")
		)
		(fp_line
			(start -0.120396 0.2794)
			(end 0.12065 0.2794)
			(stroke
				(width 0.1)
				(type default)
			)
			(layer "B.Fab")
		)
		(fp_line
			(start -0.120396 0.3048)
			(end -0.120396 0.2794)
			(stroke
				(width 0.1)
				(type default)
			)
			(layer "B.Fab")
		)
		(fp_line
			(start 0.12065 -0.305054)
			(end 0.12065 -0.2794)
			(stroke
				(width 0.1)
				(type default)
			)
			(layer "B.Fab")
		)
		(fp_line
			(start 0.12065 -0.2794)
			(end -0.12065 -0.2794)
			(stroke
				(width 0.1)
				(type default)
			)
			(layer "B.Fab")
		)
		(fp_line
			(start 0.12065 0.2794)
			(end 0.12065 0.3048)
			(stroke
				(width 0.1)
				(type default)
			)
			(layer "B.Fab")
		)
		(fp_line
			(start 0.12065 0.3048)
			(end 0.67945 0.3048)
			(stroke
				(width 0.1)
				(type default)
			)
			(layer "B.Fab")
		)
		(fp_line
			(start 0.67945 -0.305054)
			(end 0.12065 -0.305054)
			(stroke
				(width 0.1)
				(type default)
			)
			(layer "B.Fab")
		)
		(fp_line
			(start 0.67945 0.3048)
			(end 0.67945 -0.305054)
			(stroke
				(width 0.1)
				(type default)
			)
			(layer "B.Fab")
		)
		(pad "1" smd circle
			(at 0.40005 0 180)
			(size 0 0)
			(layers "B.Cu" "B.Mask" "B.Paste")
			(net "PVCCD_HV_CPU0_VCC")
		)
		(pad "2" smd circle
			(at -0.40005 0 180)
			(size 0 0)
			(layers "B.Cu" "B.Mask" "B.Paste")
			(net "P3V3_AUX")
		)
	)
	(footprint ""
		(layer "B.Cu")
		(at 315.110622 -53.203348)
		(property "Reference" "R4108"
			(at 0 0 0)
			(layer "B.SilkS")
			(hide yes)
			(effects
				(font
					(size 1.27 1.27)
				)
				(justify mirror)
			)
		)
		(property "Value" ""
			(at 0 0 0)
			(layer "B.Fab")
			(effects
				(font
					(size 1.27 1.27)
				)
				(justify mirror)
			)
		)
		(duplicate_pad_numbers_are_jumpers no)
		(fp_line
			(start -0.7874 -0.4064)
			(end -0.7874 0.4064)
			(stroke
				(width 0.1524)
				(type default)
			)
			(layer "B.SilkS")
		)
		(fp_line
			(start -0.7874 0.4064)
			(end 0.7874 0.4064)
			(stroke
				(width 0.1524)
				(type default)
			)
			(layer "B.SilkS")
		)
		(fp_line
			(start 0.7874 -0.4064)
			(end -0.7874 -0.4064)
			(stroke
				(width 0.1524)
				(type default)
			)
			(layer "B.SilkS")
		)
		(fp_line
			(start 0.7874 0.4064)
			(end 0.7874 -0.4064)
			(stroke
				(width 0.1524)
				(type default)
			)
			(layer "B.SilkS")
		)
		(fp_line
			(start -0.67945 -0.3048)
			(end -0.67945 0.3048)
			(stroke
				(width 0.1)
				(type default)
			)
			(layer "B.Fab")
		)
		(fp_line
			(start -0.67945 0.3048)
			(end -0.120396 0.3048)
			(stroke
				(width 0.1)
				(type default)
			)
			(layer "B.Fab")
		)
		(fp_line
			(start -0.12065 -0.3048)
			(end -0.67945 -0.3048)
			(stroke
				(width 0.1)
				(type default)
			)
			(layer "B.Fab")
		)
		(fp_line
			(start -0.12065 -0.2794)
			(end -0.12065 -0.3048)
			(stroke
				(width 0.1)
				(type default)
			)
			(layer "B.Fab")
		)
		(fp_line
			(start -0.120396 0.2794)
			(end 0.12065 0.2794)
			(stroke
				(width 0.1)
				(type default)
			)
			(layer "B.Fab")
		)
		(fp_line
			(start -0.120396 0.3048)
			(end -0.120396 0.2794)
			(stroke
				(width 0.1)
				(type default)
			)
			(layer "B.Fab")
		)
		(fp_line
			(start 0.12065 -0.305054)
			(end 0.12065 -0.2794)
			(stroke
				(width 0.1)
				(type default)
			)
			(layer "B.Fab")
		)
		(fp_line
			(start 0.12065 -0.2794)
			(end -0.12065 -0.2794)
			(stroke
				(width 0.1)
				(type default)
			)
			(layer "B.Fab")
		)
		(fp_line
			(start 0.12065 0.2794)
			(end 0.12065 0.3048)
			(stroke
				(width 0.1)
				(type default)
			)
			(layer "B.Fab")
		)
		(fp_line
			(start 0.12065 0.3048)
			(end 0.67945 0.3048)
			(stroke
				(width 0.1)
				(type default)
			)
			(layer "B.Fab")
		)
		(fp_line
			(start 0.67945 -0.305054)
			(end 0.12065 -0.305054)
			(stroke
				(width 0.1)
				(type default)
			)
			(layer "B.Fab")
		)
		(fp_line
			(start 0.67945 0.3048)
			(end 0.67945 -0.305054)
			(stroke
				(width 0.1)
				(type default)
			)
			(layer "B.Fab")
		)
		(pad "1" smd circle
			(at 0.40005 0 180)
			(size 0 0)
			(layers "B.Cu" "B.Mask" "B.Paste")
			(net "PD_GPP_I_16")
		)
		(pad "2" smd circle
			(at -0.40005 0 180)
			(size 0 0)
			(layers "B.Cu" "B.Mask" "B.Paste")
			(net "GND")
		)
	)
	(footprint ""
		(layer "B.Cu")
		(at 387.90499 -190.82131 90)
		(property "Reference" "R322"
			(at 0 0 90)
			(layer "B.SilkS")
			(hide yes)
			(effects
				(font
					(size 1.27 1.27)
				)
				(justify mirror)
			)
		)
		(property "Value" ""
			(at 0 0 90)
			(layer "B.Fab")
			(effects
				(font
					(size 1.27 1.27)
				)
				(justify mirror)
			)
		)
		(duplicate_pad_numbers_are_jumpers no)
		(fp_line
			(start 0.7874 -0.4064)
			(end -0.7874 -0.4064)
			(stroke
				(width 0.1524)
				(type default)
			)
			(layer "B.SilkS")
		)
		(fp_line
			(start -0.7874 -0.4064)
			(end -0.7874 0.4064)
			(stroke
				(width 0.1524)
				(type default)
			)
			(layer "B.SilkS")
		)
		(fp_line
			(start 0.7874 0.4064)
			(end 0.7874 -0.4064)
			(stroke
				(width 0.1524)
				(type default)
			)
			(layer "B.SilkS")
		)
		(fp_line
			(start -0.7874 0.4064)
			(end 0.7874 0.4064)
			(stroke
				(width 0.1524)
				(type default)
			)
			(layer "B.SilkS")
		)
		(fp_line
			(start 0.67945 -0.305054)
			(end 0.12065 -0.305054)
			(stroke
				(width 0.1)
				(type default)
			)
			(layer "B.Fab")
		)
		(fp_line
			(start 0.12065 -0.305054)
			(end 0.12065 -0.2794)
			(stroke
				(width 0.1)
				(type default)
			)
			(layer "B.Fab")
		)
		(fp_line
			(start -0.12065 -0.3048)
			(end -0.67945 -0.3048)
			(stroke
				(width 0.1)
				(type default)
			)
			(layer "B.Fab")
		)
		(fp_line
			(start -0.67945 -0.3048)
			(end -0.67945 0.3048)
			(stroke
				(width 0.1)
				(type default)
			)
			(layer "B.Fab")
		)
		(fp_line
			(start 0.12065 -0.2794)
			(end -0.12065 -0.2794)
			(stroke
				(width 0.1)
				(type default)
			)
			(layer "B.Fab")
		)
		(fp_line
			(start -0.12065 -0.2794)
			(end -0.12065 -0.3048)
			(stroke
				(width 0.1)
				(type default)
			)
			(layer "B.Fab")
		)
		(fp_line
			(start 0.12065 0.2794)
			(end 0.12065 0.3048)
			(stroke
				(width 0.1)
				(type default)
			)
			(layer "B.Fab")
		)
		(fp_line
			(start -0.120396 0.2794)
			(end 0.12065 0.2794)
			(stroke
				(width 0.1)
				(type default)
			)
			(layer "B.Fab")
		)
		(fp_line
			(start 0.67945 0.3048)
			(end 0.67945 -0.305054)
			(stroke
				(width 0.1)
				(type default)
			)
			(layer "B.Fab")
		)
		(fp_line
			(start 0.12065 0.3048)
			(end 0.67945 0.3048)
			(stroke
				(width 0.1)
				(type default)
			)
			(layer "B.Fab")
		)
		(fp_line
			(start -0.120396 0.3048)
			(end -0.120396 0.2794)
			(stroke
				(width 0.1)
				(type default)
			)
			(layer "B.Fab")
		)
		(fp_line
			(start -0.67945 0.3048)
			(end -0.120396 0.3048)
			(stroke
				(width 0.1)
				(type default)
			)
			(layer "B.Fab")
		)
		(pad "1" smd circle
			(at 0.40005 0 270)
			(size 0 0)
			(layers "B.Cu" "B.Mask" "B.Paste")
			(net "H_CPU0_PMSYNC_CPU1_R")
		)
		(pad "2" smd circle
			(at -0.40005 0 270)
			(size 0 0)
			(layers "B.Cu" "B.Mask" "B.Paste")
			(net "H_CPU0_PMSYNC_CPU1_R1")
		)
	)
	(footprint ""
		(layer "B.Cu")
		(at 180.449982 -105.120186 90)
		(property "Reference" "R166"
			(at 0 0 90)
			(layer "B.SilkS")
			(hide yes)
			(effects
				(font
					(size 1.27 1.27)
				)
				(justify mirror)
			)
		)
		(property "Value" ""
			(at 0 0 90)
			(layer "B.Fab")
			(effects
				(font
					(size 1.27 1.27)
				)
				(justify mirror)
			)
		)
		(duplicate_pad_numbers_are_jumpers no)
		(fp_line
			(start 0.7874 -0.4064)
			(end -0.7874 -0.4064)
			(stroke
				(width 0.1524)
				(type default)
			)
			(layer "B.SilkS")
		)
		(fp_line
			(start -0.7874 -0.4064)
			(end -0.7874 0.4064)
			(stroke
				(width 0.1524)
				(type default)
			)
			(layer "B.SilkS")
		)
		(fp_line
			(start 0.7874 0.4064)
			(end 0.7874 -0.4064)
			(stroke
				(width 0.1524)
				(type default)
			)
			(layer "B.SilkS")
		)
		(fp_line
			(start -0.7874 0.4064)
			(end 0.7874 0.4064)
			(stroke
				(width 0.1524)
				(type default)
			)
			(layer "B.SilkS")
		)
		(fp_line
			(start 0.67945 -0.305054)
			(end 0.12065 -0.305054)
			(stroke
				(width 0.1)
				(type default)
			)
			(layer "B.Fab")
		)
		(fp_line
			(start 0.12065 -0.305054)
			(end 0.12065 -0.2794)
			(stroke
				(width 0.1)
				(type default)
			)
			(layer "B.Fab")
		)
		(fp_line
			(start -0.12065 -0.3048)
			(end -0.67945 -0.3048)
			(stroke
				(width 0.1)
				(type default)
			)
			(layer "B.Fab")
		)
		(fp_line
			(start -0.67945 -0.3048)
			(end -0.67945 0.3048)
			(stroke
				(width 0.1)
				(type default)
			)
			(layer "B.Fab")
		)
		(fp_line
			(start 0.12065 -0.2794)
			(end -0.12065 -0.2794)
			(stroke
				(width 0.1)
				(type default)
			)
			(layer "B.Fab")
		)
		(fp_line
			(start -0.12065 -0.2794)
			(end -0.12065 -0.3048)
			(stroke
				(width 0.1)
				(type default)
			)
			(layer "B.Fab")
		)
		(fp_line
			(start 0.12065 0.2794)
			(end 0.12065 0.3048)
			(stroke
				(width 0.1)
				(type default)
			)
			(layer "B.Fab")
		)
		(fp_line
			(start -0.120396 0.2794)
			(end 0.12065 0.2794)
			(stroke
				(width 0.1)
				(type default)
			)
			(layer "B.Fab")
		)
		(fp_line
			(start 0.67945 0.3048)
			(end 0.67945 -0.305054)
			(stroke
				(width 0.1)
				(type default)
			)
			(layer "B.Fab")
		)
		(fp_line
			(start 0.12065 0.3048)
			(end 0.67945 0.3048)
			(stroke
				(width 0.1)
				(type default)
			)
			(layer "B.Fab")
		)
		(fp_line
			(start -0.120396 0.3048)
			(end -0.120396 0.2794)
			(stroke
				(width 0.1)
				(type default)
			)
			(layer "B.Fab")
		)
		(fp_line
			(start -0.67945 0.3048)
			(end -0.120396 0.3048)
			(stroke
				(width 0.1)
				(type default)
			)
			(layer "B.Fab")
		)
		(pad "1" smd circle
			(at 0.40005 0 270)
			(size 0 0)
			(layers "B.Cu" "B.Mask" "B.Paste")
			(net "PWRGD_DRAMPWRGD_CPU0_GH_R_LVC1")
		)
		(pad "2" smd circle
			(at -0.40005 0 270)
			(size 0 0)
			(layers "B.Cu" "B.Mask" "B.Paste")
			(net "PWRGD_DRAMPWRGD_CPU0_GH_LVC1_R2")
		)
	)
	(footprint ""
		(layer "B.Cu")
		(at 283.82468 -354.028502 -90)
		(property "Reference" "PR4265"
			(at 0 0 90)
			(layer "B.SilkS")
			(hide yes)
			(effects
				(font
					(size 1.27 1.27)
				)
				(justify mirror)
			)
		)
		(property "Value" ""
			(at 0 0 90)
			(layer "B.Fab")
			(effects
				(font
					(size 1.27 1.27)
				)
				(justify mirror)
			)
		)
		(duplicate_pad_numbers_are_jumpers no)
		(fp_line
			(start -0.7874 0.4064)
			(end 0.7874 0.4064)
			(stroke
				(width 0.1524)
				(type default)
			)
			(layer "B.SilkS")
		)
		(fp_line
			(start 0.7874 0.4064)
			(end 0.7874 -0.4064)
			(stroke
				(width 0.1524)
				(type default)
			)
			(layer "B.SilkS")
		)
		(fp_line
			(start -0.7874 -0.4064)
			(end -0.7874 0.4064)
			(stroke
				(width 0.1524)
				(type default)
			)
			(layer "B.SilkS")
		)
		(fp_line
			(start 0.7874 -0.4064)
			(end -0.7874 -0.4064)
			(stroke
				(width 0.1524)
				(type default)
			)
			(layer "B.SilkS")
		)
		(fp_line
			(start -0.67945 0.3048)
			(end -0.120396 0.3048)
			(stroke
				(width 0.1)
				(type default)
			)
			(layer "B.Fab")
		)
		(fp_line
			(start -0.120396 0.3048)
			(end -0.120396 0.2794)
			(stroke
				(width 0.1)
				(type default)
			)
			(layer "B.Fab")
		)
		(fp_line
			(start 0.12065 0.3048)
			(end 0.67945 0.3048)
			(stroke
				(width 0.1)
				(type default)
			)
			(layer "B.Fab")
		)
		(fp_line
			(start 0.67945 0.3048)
			(end 0.67945 -0.305054)
			(stroke
				(width 0.1)
				(type default)
			)
			(layer "B.Fab")
		)
		(fp_line
			(start -0.120396 0.2794)
			(end 0.12065 0.2794)
			(stroke
				(width 0.1)
				(type default)
			)
			(layer "B.Fab")
		)
		(fp_line
			(start 0.12065 0.2794)
			(end 0.12065 0.3048)
			(stroke
				(width 0.1)
				(type default)
			)
			(layer "B.Fab")
		)
		(fp_line
			(start -0.12065 -0.2794)
			(end -0.12065 -0.3048)
			(stroke
				(width 0.1)
				(type default)
			)
			(layer "B.Fab")
		)
		(fp_line
			(start 0.12065 -0.2794)
			(end -0.12065 -0.2794)
			(stroke
				(width 0.1)
				(type default)
			)
			(layer "B.Fab")
		)
		(fp_line
			(start -0.67945 -0.3048)
			(end -0.67945 0.3048)
			(stroke
				(width 0.1)
				(type default)
			)
			(layer "B.Fab")
		)
		(fp_line
			(start -0.12065 -0.3048)
			(end -0.67945 -0.3048)
			(stroke
				(width 0.1)
				(type default)
			)
			(layer "B.Fab")
		)
		(fp_line
			(start 0.12065 -0.305054)
			(end 0.12065 -0.2794)
			(stroke
				(width 0.1)
				(type default)
			)
			(layer "B.Fab")
		)
		(fp_line
			(start 0.67945 -0.305054)
			(end 0.12065 -0.305054)
			(stroke
				(width 0.1)
				(type default)
			)
			(layer "B.Fab")
		)
		(pad "1" smd circle
			(at 0.40005 0 90)
			(size 0 0)
			(layers "B.Cu" "B.Mask" "B.Paste")
			(net "PVCCFA_EHV_FIVRA_CPU0")
		)
		(pad "2" smd circle
			(at -0.40005 0 90)
			(size 0 0)
			(layers "B.Cu" "B.Mask" "B.Paste")
			(net "GND")
		)
	)
	(footprint ""
		(layer "B.Cu")
		(at 272.444972 -68.4784)
		(property "Reference" "PC1226"
			(at 0 0 0)
			(layer "B.SilkS")
			(hide yes)
			(effects
				(font
					(size 1.27 1.27)
				)
				(justify mirror)
			)
		)
		(property "Value" ""
			(at 0 0 0)
			(layer "B.Fab")
			(effects
				(font
					(size 1.27 1.27)
				)
				(justify mirror)
			)
		)
		(duplicate_pad_numbers_are_jumpers no)
		(fp_line
			(start -1.524 -0.762)
			(end -1.524 0.762)
			(stroke
				(width 0.1524)
				(type default)
			)
			(layer "B.SilkS")
		)
		(fp_line
			(start -1.524 0.762)
			(end 1.524 0.762)
			(stroke
				(width 0.1524)
				(type default)
			)
			(layer "B.SilkS")
		)
		(fp_line
			(start 1.524 -0.762)
			(end -1.524 -0.762)
			(stroke
				(width 0.1524)
				(type default)
			)
			(layer "B.SilkS")
		)
		(fp_line
			(start 1.524 0.762)
			(end 1.524 -0.762)
			(stroke
				(width 0.1524)
				(type default)
			)
			(layer "B.SilkS")
		)
		(fp_line
			(start -1.1049 -0.724916)
			(end 1.1049 -0.724916)
			(stroke
				(width 0.1)
				(type default)
			)
			(layer "B.Fab")
		)
		(fp_line
			(start -1.1049 0.724916)
			(end -1.1049 -0.724916)
			(stroke
				(width 0.1)
				(type default)
			)
			(layer "B.Fab")
		)
		(fp_line
			(start 1.1049 -0.724916)
			(end 1.1049 0.724916)
			(stroke
				(width 0.1)
				(type default)
			)
			(layer "B.Fab")
		)
		(fp_line
			(start 1.1049 0.724916)
			(end -1.1049 0.724916)
			(stroke
				(width 0.1)
				(type default)
			)
			(layer "B.Fab")
		)
		(pad "1" smd rect
			(at 0.889 0)
			(size 1.016 1.27)
			(layers "B.Cu" "B.Mask" "B.Paste")
			(net "P1V05_PCH_AUX")
		)
		(pad "2" smd rect
			(at -0.889 0)
			(size 1.016 1.27)
			(layers "B.Cu" "B.Mask" "B.Paste")
			(net "GND")
		)
	)
	(footprint ""
		(layer "B.Cu")
		(at 186.331352 -344.656664 -90)
		(property "Reference" "PC1206_P1_3"
			(at 0 0 90)
			(layer "B.SilkS")
			(hide yes)
			(effects
				(font
					(size 1.27 1.27)
				)
				(justify mirror)
			)
		)
		(property "Value" ""
			(at 0 0 90)
			(layer "B.Fab")
			(effects
				(font
					(size 1.27 1.27)
				)
				(justify mirror)
			)
		)
		(duplicate_pad_numbers_are_jumpers no)
		(fp_line
			(start -1.524 0.762)
			(end 1.524 0.762)
			(stroke
				(width 0.1524)
				(type default)
			)
			(layer "B.SilkS")
		)
		(fp_line
			(start 1.524 0.762)
			(end 1.524 -0.762)
			(stroke
				(width 0.1524)
				(type default)
			)
			(layer "B.SilkS")
		)
		(fp_line
			(start -1.524 -0.762)
			(end -1.524 0.762)
			(stroke
				(width 0.1524)
				(type default)
			)
			(layer "B.SilkS")
		)
		(fp_line
			(start 1.524 -0.762)
			(end -1.524 -0.762)
			(stroke
				(width 0.1524)
				(type default)
			)
			(layer "B.SilkS")
		)
		(fp_line
			(start -1.1049 0.724916)
			(end -1.1049 -0.724916)
			(stroke
				(width 0.1)
				(type default)
			)
			(layer "B.Fab")
		)
		(fp_line
			(start 1.1049 0.724916)
			(end -1.1049 0.724916)
			(stroke
				(width 0.1)
				(type default)
			)
			(layer "B.Fab")
		)
		(fp_line
			(start -1.1049 -0.724916)
			(end 1.1049 -0.724916)
			(stroke
				(width 0.1)
				(type default)
			)
			(layer "B.Fab")
		)
		(fp_line
			(start 1.1049 -0.724916)
			(end 1.1049 0.724916)
			(stroke
				(width 0.1)
				(type default)
			)
			(layer "B.Fab")
		)
		(pad "1" smd rect
			(at 0.889 0 270)
			(size 1.016 1.27)
			(layers "B.Cu" "B.Mask" "B.Paste")
			(net "PVCCFA_EHV_FIVRA_CPU1")
		)
		(pad "2" smd rect
			(at -0.889 0 270)
			(size 1.016 1.27)
			(layers "B.Cu" "B.Mask" "B.Paste")
			(net "GND")
		)
	)
)
